(kicad_pcb
	(version 20221018)
	(generator pcbnew)
	(general
    (thickness 1.7403)
  )
	(paper "A4")
	(title_block
    (title "Data Center RDIMM DDR4 Tester")
    (date "2024-09-30")
    (rev "1.2.4")
		(comment 9 "footprints 374-382 of 690")
	)
	(layers
    (0 "F.Cu" signal)
    (1 "In1.Cu" power)
    (2 "In2.Cu" signal)
    (3 "In3.Cu" power)
    (4 "In4.Cu" power)
    (5 "In5.Cu" signal)
    (6 "In6.Cu" power)
    (7 "In7.Cu" signal)
    (8 "In8.Cu" power)
    (9 "In9.Cu" signal)
    (10 "In10.Cu" power)
    (31 "B.Cu" signal)
    (32 "B.Adhes" user "B.Adhesive")
    (33 "F.Adhes" user "F.Adhesive")
    (34 "B.Paste" user)
    (35 "F.Paste" user)
    (36 "B.SilkS" user "B.Silkscreen")
    (37 "F.SilkS" user "F.Silkscreen")
    (38 "B.Mask" user)
    (39 "F.Mask" user)
    (40 "Dwgs.User" user "User.Drawings")
    (41 "Cmts.User" user "User.Comments")
    (42 "Eco1.User" user "User.Eco1")
    (43 "Eco2.User" user "User.Eco2")
    (44 "Edge.Cuts" user)
    (45 "Margin" user)
    (46 "B.CrtYd" user "B.Courtyard")
    (47 "F.CrtYd" user "F.Courtyard")
    (48 "B.Fab" user)
    (49 "F.Fab" user)
  )
	(footprint "data-center-rdimm-ddr4-tester-footprints:R_1206_3216Metric" (layer "F.Cu")
    (at 112.45 91.5 90)
    (property "Author" "Antmicro")
    (property "License" "Apache-2.0")
    (property "MPN" "RL1206FR-7W0R01L")
    (property "Manufacturer" "Yaego")
    (property "Sheetfile" "supply.kicad_sch")
    (property "Sheetname" "Supply")
    (property "Tolerance" "1%")
    (property "Val" "0R01")
    (property "ki_description" "0R01 resistor in 1206 package with unspecified tolerance")
    (attr smd)
    (fp_text reference "R200" (at -1.36 -1.05 90) (layer "F.SilkS")
        (effects (font (size 0.7 0.7) (thickness 0.15)) (justify left bottom))
    )
    (fp_text value "R_0R01_1206" (at 0 2 90) (layer "F.Fab") hide
        (effects (font (size 0.7 0.7) (thickness 0.15)) (justify left bottom))
    )
    (fp_text user "Author: Antmicro" (at -2.401 4.899 90) (layer "F.Fab") hide
        (effects (font (size 0.7 0.7) (thickness 0.15)) (justify left bottom))
    )
    (fp_text user "License: Apache-2.0" (at -2.401 6.3 90) (layer "F.Fab") hide
        (effects (font (size 0.7 0.7) (thickness 0.15)) (justify left bottom))
    )
    (fp_text user "${REFERENCE}" (at -2.401 3.5 90) (layer "F.Fab") hide
        (effects (font (size 0.7 0.7) (thickness 0.15)) (justify left bottom))
    )
    (fp_line (start 0 -0.902) (end -0.5 -0.902)
      (stroke (width 0.15) (type solid)) (layer "F.SilkS"))
    (fp_line (start 0 -0.902) (end 0.498 -0.902)
      (stroke (width 0.15) (type solid)) (layer "F.SilkS"))
    (fp_line (start 0 0.9) (end -0.5 0.9)
      (stroke (width 0.15) (type solid)) (layer "F.SilkS"))
    (fp_line (start 0 0.9) (end 0.498 0.9)
      (stroke (width 0.15) (type solid)) (layer "F.SilkS"))
    (fp_rect (start -2.25 -1.05) (end 2.25 1.05)
      (stroke (width 0.05) (type solid)) (fill none) (layer "F.CrtYd"))
    (fp_line (start -1.601 -0.802) (end -1.601 0.8)
      (stroke (width 0.15) (type solid)) (layer "F.Fab"))
    (fp_line (start -1.601 -0.802) (end 1.6 -0.802)
      (stroke (width 0.15) (type solid)) (layer "F.Fab"))
    (fp_line (start -1.601 0.8) (end 1.6 0.8)
      (stroke (width 0.15) (type solid)) (layer "F.Fab"))
    (fp_line (start 1.6 -0.802) (end 1.6 0.8)
      (stroke (width 0.15) (type solid)) (layer "F.Fab"))
    (pad "1" smd roundrect (at -1.5 0 90) (size 1.2 1.8) (layers "F.Cu" "F.Paste" "F.Mask") (roundrect_rratio 0.15)
      (net 299 "VCC0V6") (pintype "passive"))
    (pad "2" smd roundrect (at 1.499 0 90) (size 1.2 1.8) (layers "F.Cu" "F.Paste" "F.Mask") (roundrect_rratio 0.15)
      (net 186 "VTT") (pintype "passive"))
  )
	(footprint "data-center-rdimm-ddr4-tester-footprints:R_0402_1005Metric" (layer "B.Cu")
    (at 140.25 118.507)
    (descr "Resistor SMD 0402")
    (tags "resistor SMD 0402")
    (property "Author" "Antmicro")
    (property "License" "Apache-2.0")
    (property "MPN" "CR0402-FX-2002GLF")
    (property "Manufacturer" "Bourns")
    (property "Sheetfile" "interfaces.kicad_sch")
    (property "Sheetname" "Interfaces")
    (property "Tolerance" "1%")
    (property "Val" "20k")
    (property "ki_description" "20k resistor in 0402 package with 1% tolerance")
    (attr smd)
    (fp_text reference "R131" (at 1.33 -1.517 180) (layer "B.SilkS")
        (effects (font (size 0.7 0.7) (thickness 0.15)) (justify left bottom mirror))
    )
    (fp_text value "R_20k_0402" (at 0 -1.4 180) (layer "B.Fab") hide
        (effects (font (size 0.7 0.7) (thickness 0.15)) (justify left bottom mirror))
    )
    (fp_text user "${REFERENCE}" (at -0.95 -3.168 180) (layer "B.Fab") hide
        (effects (font (size 0.7 0.7) (thickness 0.15)) (justify left bottom mirror))
    )
    (fp_text user "License: Apache-2.0" (at -0.95 -5.169 180) (layer "B.Fab") hide
        (effects (font (size 0.7 0.7) (thickness 0.15)) (justify left bottom mirror))
    )
    (fp_text user "Author: Antmicro" (at -0.95 -4.169 180) (layer "B.Fab") hide
        (effects (font (size 0.7 0.7) (thickness 0.15)) (justify left bottom mirror))
    )
    (fp_rect (start -0.93 0.47) (end 0.93 -0.47)
      (stroke (width 0.05) (type solid)) (fill none) (layer "B.CrtYd"))
    (fp_rect (start -0.5 0.25) (end 0.5 -0.25)
      (stroke (width 0.15) (type solid)) (fill none) (layer "B.Fab"))
    (pad "1" smd roundrect (at -0.485 0) (size 0.59 0.64) (layers "B.Cu" "B.Paste" "B.Mask") (roundrect_rratio 0.25)
      (net 143 "3V3_SYS") (pintype "passive"))
    (pad "2" smd roundrect (at 0.485 0) (size 0.59 0.64) (layers "B.Cu" "B.Paste" "B.Mask") (roundrect_rratio 0.25)
      (net 88 "SD_CD") (pintype "passive"))
  )
	(footprint "data-center-rdimm-ddr4-tester-footprints:R_0402_1005Metric" (layer "B.Cu")
    (at 140.25 119.65 180)
    (descr "Resistor SMD 0402")
    (tags "resistor SMD 0402")
    (property "Author" "Antmicro")
    (property "License" "Apache-2.0")
    (property "MPN" "CR0402-FX-2200GLF")
    (property "Manufacturer" "Bourns")
    (property "Sheetfile" "interfaces.kicad_sch")
    (property "Sheetname" "Interfaces")
    (property "Tolerance" "1%")
    (property "Val" "220R")
    (property "ki_description" "220R resistor in 0402 package with 1% tolerance")
    (attr smd)
    (fp_text reference "R136" (at -1.3 1.73) (layer "B.SilkS")
        (effects (font (size 0.7 0.7) (thickness 0.15)) (justify left bottom mirror))
    )
    (fp_text value "R_220R_0402" (at 0 -1.4) (layer "B.Fab") hide
        (effects (font (size 0.7 0.7) (thickness 0.15)) (justify left bottom mirror))
    )
    (fp_text user "${REFERENCE}" (at -0.95 -3.168) (layer "B.Fab") hide
        (effects (font (size 0.7 0.7) (thickness 0.15)) (justify left bottom mirror))
    )
    (fp_text user "Author: Antmicro" (at -0.95 -4.169) (layer "B.Fab") hide
        (effects (font (size 0.7 0.7) (thickness 0.15)) (justify left bottom mirror))
    )
    (fp_text user "License: Apache-2.0" (at -0.95 -5.169) (layer "B.Fab") hide
        (effects (font (size 0.7 0.7) (thickness 0.15)) (justify left bottom mirror))
    )
    (fp_rect (start -0.93 0.47) (end 0.93 -0.47)
      (stroke (width 0.05) (type solid)) (fill none) (layer "B.CrtYd"))
    (fp_rect (start -0.5 0.25) (end 0.5 -0.25)
      (stroke (width 0.15) (type solid)) (fill none) (layer "B.Fab"))
    (pad "1" smd roundrect (at -0.485 0 180) (size 0.59 0.64) (layers "B.Cu" "B.Paste" "B.Mask") (roundrect_rratio 0.25)
      (net 88 "SD_CD") (pintype "passive"))
    (pad "2" smd roundrect (at 0.485 0 180) (size 0.59 0.64) (layers "B.Cu" "B.Paste" "B.Mask") (roundrect_rratio 0.25)
      (net 564 "Net-(J7-CD_SW1)") (pintype "passive"))
  )
	(footprint "data-center-rdimm-ddr4-tester-footprints:R_0402_1005Metric" (layer "B.Cu")
    (at 140.536328 92.370008 -90)
    (descr "Resistor SMD 0402")
    (tags "resistor SMD 0402")
    (property "Author" "Antmicro")
    (property "License" "Apache-2.0")
    (property "MPN" "CR0402-FX-1002GLF")
    (property "Manufacturer" "Bourns")
    (property "Sheetfile" "supply.kicad_sch")
    (property "Sheetname" "Supply")
    (property "Tolerance" "1%")
    (property "Val" "10k")
    (property "ki_description" "10k resistor in 0402 package with 1% tolerance")
    (attr smd)
    (fp_text reference "R86" (at -2.990008 -0.413672 90) (layer "B.SilkS")
        (effects (font (size 0.7 0.7) (thickness 0.15)) (justify left bottom mirror))
    )
    (fp_text value "R_10k_0402" (at 0 -1.4 90) (layer "B.Fab") hide
        (effects (font (size 0.7 0.7) (thickness 0.15)) (justify left bottom mirror))
    )
    (fp_text user "Author: Antmicro" (at -0.95 -4.169 90) (layer "B.Fab") hide
        (effects (font (size 0.7 0.7) (thickness 0.15)) (justify left bottom mirror))
    )
    (fp_text user "License: Apache-2.0" (at -0.95 -5.169 90) (layer "B.Fab") hide
        (effects (font (size 0.7 0.7) (thickness 0.15)) (justify left bottom mirror))
    )
    (fp_text user "${REFERENCE}" (at -0.95 -3.168 90) (layer "B.Fab") hide
        (effects (font (size 0.7 0.7) (thickness 0.15)) (justify left bottom mirror))
    )
    (fp_rect (start -0.93 0.47) (end 0.93 -0.47)
      (stroke (width 0.05) (type solid)) (fill none) (layer "B.CrtYd"))
    (fp_rect (start -0.5 0.25) (end 0.5 -0.25)
      (stroke (width 0.15) (type solid)) (fill none) (layer "B.Fab"))
    (pad "1" smd roundrect (at -0.485 0 270) (size 0.59 0.64) (layers "B.Cu" "B.Paste" "B.Mask") (roundrect_rratio 0.25)
      (net 307 "5V0_SYS") (pintype "passive"))
    (pad "2" smd roundrect (at 0.485 0 270) (size 0.59 0.64) (layers "B.Cu" "B.Paste" "B.Mask") (roundrect_rratio 0.25)
      (net 151 "/Supply/VCC_INT_EN") (pintype "passive"))
  )
	(footprint "data-center-rdimm-ddr4-tester-footprints:R_0402_1005Metric" (layer "B.Cu")
    (at 141.536328 92.370008 -90)
    (descr "Resistor SMD 0402")
    (tags "resistor SMD 0402")
    (property "Author" "Antmicro")
    (property "License" "Apache-2.0")
    (property "MPN" "CR0402-FX-1002GLF")
    (property "Manufacturer" "Bourns")
    (property "Sheetfile" "supply.kicad_sch")
    (property "Sheetname" "Supply")
    (property "Tolerance" "1%")
    (property "Val" "10k")
    (property "ki_description" "10k resistor in 0402 package with 1% tolerance")
    (attr smd)
    (fp_text reference "R87" (at -2.990008 -0.413672 90) (layer "B.SilkS")
        (effects (font (size 0.7 0.7) (thickness 0.15)) (justify left bottom mirror))
    )
    (fp_text value "R_10k_0402" (at 0 -1.4 90) (layer "B.Fab") hide
        (effects (font (size 0.7 0.7) (thickness 0.15)) (justify left bottom mirror))
    )
    (fp_text user "License: Apache-2.0" (at -0.95 -5.169 90) (layer "B.Fab") hide
        (effects (font (size 0.7 0.7) (thickness 0.15)) (justify left bottom mirror))
    )
    (fp_text user "${REFERENCE}" (at -0.95 -3.168 90) (layer "B.Fab") hide
        (effects (font (size 0.7 0.7) (thickness 0.15)) (justify left bottom mirror))
    )
    (fp_text user "Author: Antmicro" (at -0.95 -4.169 90) (layer "B.Fab") hide
        (effects (font (size 0.7 0.7) (thickness 0.15)) (justify left bottom mirror))
    )
    (fp_rect (start -0.93 0.47) (end 0.93 -0.47)
      (stroke (width 0.05) (type solid)) (fill none) (layer "B.CrtYd"))
    (fp_rect (start -0.5 0.25) (end 0.5 -0.25)
      (stroke (width 0.15) (type solid)) (fill none) (layer "B.Fab"))
    (pad "1" smd roundrect (at -0.485 0 270) (size 0.59 0.64) (layers "B.Cu" "B.Paste" "B.Mask") (roundrect_rratio 0.25)
      (net 307 "5V0_SYS") (pintype "passive"))
    (pad "2" smd roundrect (at 0.485 0 270) (size 0.59 0.64) (layers "B.Cu" "B.Paste" "B.Mask") (roundrect_rratio 0.25)
      (net 152 "/Supply/VCC_AUX_EN") (pintype "passive"))
  )
	(footprint "data-center-rdimm-ddr4-tester-footprints:R_0402_1005Metric" (layer "B.Cu")
    (at 142.536328 92.370008 -90)
    (descr "Resistor SMD 0402")
    (tags "resistor SMD 0402")
    (property "Author" "Antmicro")
    (property "License" "Apache-2.0")
    (property "MPN" "CR0402-FX-1002GLF")
    (property "Manufacturer" "Bourns")
    (property "Sheetfile" "supply.kicad_sch")
    (property "Sheetname" "Supply")
    (property "Tolerance" "1%")
    (property "Val" "10k")
    (property "ki_description" "10k resistor in 0402 package with 1% tolerance")
    (attr smd)
    (fp_text reference "R88" (at -2.990008 -0.413672 90) (layer "B.SilkS")
        (effects (font (size 0.7 0.7) (thickness 0.15)) (justify left bottom mirror))
    )
    (fp_text value "R_10k_0402" (at 0 -1.4 90) (layer "B.Fab") hide
        (effects (font (size 0.7 0.7) (thickness 0.15)) (justify left bottom mirror))
    )
    (fp_text user "License: Apache-2.0" (at -0.95 -5.169 90) (layer "B.Fab") hide
        (effects (font (size 0.7 0.7) (thickness 0.15)) (justify left bottom mirror))
    )
    (fp_text user "Author: Antmicro" (at -0.95 -4.169 90) (layer "B.Fab") hide
        (effects (font (size 0.7 0.7) (thickness 0.15)) (justify left bottom mirror))
    )
    (fp_text user "${REFERENCE}" (at -0.95 -3.168 90) (layer "B.Fab") hide
        (effects (font (size 0.7 0.7) (thickness 0.15)) (justify left bottom mirror))
    )
    (fp_rect (start -0.93 0.47) (end 0.93 -0.47)
      (stroke (width 0.05) (type solid)) (fill none) (layer "B.CrtYd"))
    (fp_rect (start -0.5 0.25) (end 0.5 -0.25)
      (stroke (width 0.15) (type solid)) (fill none) (layer "B.Fab"))
    (pad "1" smd roundrect (at -0.485 0 270) (size 0.59 0.64) (layers "B.Cu" "B.Paste" "B.Mask") (roundrect_rratio 0.25)
      (net 307 "5V0_SYS") (pintype "passive"))
    (pad "2" smd roundrect (at 0.485 0 270) (size 0.59 0.64) (layers "B.Cu" "B.Paste" "B.Mask") (roundrect_rratio 0.25)
      (net 153 "/Supply/VCC_IO_EN") (pintype "passive"))
  )
	(footprint "data-center-rdimm-ddr4-tester-footprints:R_0402_1005Metric" (layer "B.Cu")
    (at 241.1 121.2 180)
    (descr "Resistor SMD 0402")
    (tags "resistor SMD 0402")
    (property "Author" "Antmicro")
    (property "License" "Apache-2.0")
    (property "MPN" "CR0402-FX-3300GLF")
    (property "Manufacturer" "Bourns")
    (property "Sheetfile" "supply.kicad_sch")
    (property "Sheetname" "Supply")
    (property "Tolerance" "1%")
    (property "Val" "330R")
    (property "ki_description" "330R resistor in 0402 package with 1% tolerance")
    (attr smd)
    (fp_text reference "R119" (at 0.87 -0.37) (layer "B.SilkS")
        (effects (font (size 0.7 0.7) (thickness 0.15)) (justify left bottom mirror))
    )
    (fp_text value "R_330R_0402" (at 0 -1.4) (layer "B.Fab") hide
        (effects (font (size 0.7 0.7) (thickness 0.15)) (justify left bottom mirror))
    )
    (fp_text user "License: Apache-2.0" (at -0.95 -5.169) (layer "B.Fab") hide
        (effects (font (size 0.7 0.7) (thickness 0.15)) (justify left bottom mirror))
    )
    (fp_text user "Author: Antmicro" (at -0.95 -4.169) (layer "B.Fab") hide
        (effects (font (size 0.7 0.7) (thickness 0.15)) (justify left bottom mirror))
    )
    (fp_text user "${REFERENCE}" (at -0.95 -3.168) (layer "B.Fab") hide
        (effects (font (size 0.7 0.7) (thickness 0.15)) (justify left bottom mirror))
    )
    (fp_rect (start -0.93 0.47) (end 0.93 -0.47)
      (stroke (width 0.05) (type solid)) (fill none) (layer "B.CrtYd"))
    (fp_rect (start -0.5 0.25) (end 0.5 -0.25)
      (stroke (width 0.15) (type solid)) (fill none) (layer "B.Fab"))
    (pad "1" smd roundrect (at -0.485 0 180) (size 0.59 0.64) (layers "B.Cu" "B.Paste" "B.Mask") (roundrect_rratio 0.25)
      (net 115 "Net-(PWR1-Pad2)") (pintype "passive"))
    (pad "2" smd roundrect (at 0.485 0 180) (size 0.59 0.64) (layers "B.Cu" "B.Paste" "B.Mask") (roundrect_rratio 0.25)
      (net 9 "GND") (pintype "passive"))
  )
	(footprint "data-center-rdimm-ddr4-tester-footprints:R_0402_1005Metric" (layer "B.Cu")
    (at 197.386328 92.810008 90)
    (descr "Resistor SMD 0402")
    (tags "resistor SMD 0402")
    (property "Author" "Antmicro")
    (property "Current" "1A")
    (property "License" "Apache-2.0")
    (property "MPN" "ERJ2GE0R00X")
    (property "Manufacturer" "Panasonic")
    (property "Sheetfile" "config-spi.kicad_sch")
    (property "Sheetname" "Config SPI flash")
    (property "Tolerance" "")
    (property "Val" "0R")
    (property "ki_description" "0R resistor in 0402 package with unspecified tolerance")
    (attr smd)
    (fp_text reference "R58" (at 1.020008 2.383672 270) (layer "B.SilkS")
        (effects (font (size 0.7 0.7) (thickness 0.15)) (justify left bottom mirror))
    )
    (fp_text value "R_0R_0402" (at 0 -1.4 270) (layer "B.Fab") hide
        (effects (font (size 0.7 0.7) (thickness 0.15)) (justify left bottom mirror))
    )
    (fp_text user "License: Apache-2.0" (at -0.95 -5.169 270) (layer "B.Fab") hide
        (effects (font (size 0.7 0.7) (thickness 0.15)) (justify left bottom mirror))
    )
    (fp_text user "${REFERENCE}" (at -0.95 -3.168 270) (layer "B.Fab") hide
        (effects (font (size 0.7 0.7) (thickness 0.15)) (justify left bottom mirror))
    )
    (fp_text user "Author: Antmicro" (at -0.95 -4.169 270) (layer "B.Fab") hide
        (effects (font (size 0.7 0.7) (thickness 0.15)) (justify left bottom mirror))
    )
    (fp_rect (start -0.93 0.47) (end 0.93 -0.47)
      (stroke (width 0.05) (type solid)) (fill none) (layer "B.CrtYd"))
    (fp_rect (start -0.5 0.25) (end 0.5 -0.25)
      (stroke (width 0.15) (type solid)) (fill none) (layer "B.Fab"))
    (pad "1" smd roundrect (at -0.485 0 90) (size 0.59 0.64) (layers "B.Cu" "B.Paste" "B.Mask") (roundrect_rratio 0.25)
      (net 143 "3V3_SYS") (pintype "passive"))
    (pad "2" smd roundrect (at 0.485 0 90) (size 0.59 0.64) (layers "B.Cu" "B.Paste" "B.Mask") (roundrect_rratio 0.25)
      (net 100 "CFGBVS") (pintype "passive"))
  )
	(footprint "data-center-rdimm-ddr4-tester-footprints:R_0402_1005Metric" (layer "B.Cu")
    (at 157.686328 86.320008 90)
    (descr "Resistor SMD 0402")
    (tags "resistor SMD 0402")
    (property "Author" "Antmicro")
    (property "DNP" "DNP")
    (property "License" "Apache-2.0")
    (property "MPN" "CR0402-FX-1002GLF")
    (property "Manufacturer" "Bourns")
    (property "Sheetfile" "ethernet.kicad_sch")
    (property "Sheetname" "Ethernet")
    (property "Tolerance" "1%")
    (property "Val" "10k")
    (property "dnp" "")
    (property "exclude_from_bom" "")
    (property "ki_description" "10k resistor in 0402 package with 1% tolerance")
    (attr exclude_from_pos_files exclude_from_bom)
    (fp_text reference "R70" (at 1.170008 8.103672 270) (layer "B.SilkS")
        (effects (font (size 0.7 0.7) (thickness 0.15)) (justify left bottom mirror))
    )
    (fp_text value "R_10k_0402" (at 0 -1.4 270) (layer "B.Fab") hide
        (effects (font (size 0.7 0.7) (thickness 0.15)) (justify left bottom mirror))
    )
    (fp_text user "Author: Antmicro" (at -0.95 -4.169 270) (layer "B.Fab") hide
        (effects (font (size 0.7 0.7) (thickness 0.15)) (justify left bottom mirror))
    )
    (fp_text user "License: Apache-2.0" (at -0.95 -5.169 270) (layer "B.Fab") hide
        (effects (font (size 0.7 0.7) (thickness 0.15)) (justify left bottom mirror))
    )
    (fp_text user "${REFERENCE}" (at -0.95 -3.168 270) (layer "B.Fab") hide
        (effects (font (size 0.7 0.7) (thickness 0.15)) (justify left bottom mirror))
    )
    (fp_rect (start -0.93 0.47) (end 0.93 -0.47)
      (stroke (width 0.05) (type solid)) (fill none) (layer "B.CrtYd"))
    (fp_rect (start -0.5 0.25) (end 0.5 -0.25)
      (stroke (width 0.15) (type solid)) (fill none) (layer "B.Fab"))
    (pad "1" smd roundrect (at -0.485 0 90) (size 0.59 0.64) (layers "B.Cu" "B.Paste" "B.Mask") (roundrect_rratio 0.25)
      (net 26 "ETH_RXD0") (pintype "passive"))
    (pad "2" smd roundrect (at 0.485 0 90) (size 0.59 0.64) (layers "B.Cu" "B.Paste" "B.Mask") (roundrect_rratio 0.25)
      (net 143 "3V3_SYS") (pintype "passive"))
  )
)
